(kicad_pcb
	(version 20241229)
	(generator "pcbnew")
	(generator_version "9.0")
	(general
		(thickness 1.711)
		(legacy_teardrops no)
	)
	(paper "A4")
	(title_block
		(title "Antmicro Baseboard for Jetson AGX Thor")
		(date "2026-02-18")
		(rev "1.1.0")
		(company "Antmicro Ltd")
		(comment 1 "www.antmicro.com")
		(comment 9 "footprints 496-499 of 1170")
	)
	(layers
		(0 "F.Cu" signal)
		(4 "In1.Cu" signal)
		(6 "In2.Cu" signal)
		(8 "In3.Cu" signal)
		(10 "In4.Cu" jumper)
		(12 "In5.Cu" signal)
		(14 "In6.Cu" signal)
		(16 "In7.Cu" signal)
		(18 "In8.Cu" signal)
		(2 "B.Cu" signal)
		(9 "F.Adhes" user "F.Adhesive")
		(11 "B.Adhes" user "B.Adhesive")
		(13 "F.Paste" user)
		(15 "B.Paste" user)
		(5 "F.SilkS" user "F.Silkscreen")
		(7 "B.SilkS" user "B.Silkscreen")
		(1 "F.Mask" user)
		(3 "B.Mask" user)
		(17 "Dwgs.User" user "User.Drawings")
		(19 "Cmts.User" user "User.Comments")
		(21 "Eco1.User" user "User.Eco1")
		(23 "Eco2.User" user "User.Eco2")
		(25 "Edge.Cuts" user)
		(27 "Margin" user)
		(31 "F.CrtYd" user "F.Courtyard")
		(29 "B.CrtYd" user "B.Courtyard")
		(35 "F.Fab" user)
		(33 "B.Fab" user)
	)
	(footprint "antmicro-footprints:R_0402_1005Metric"
		(layer "F.Cu")
		(at 139.23 131.15 90)
		(descr "Resistor SMD 0402")
		(tags "resistor SMD 0402")
		(property "Reference" "R355"
			(at 0.85 0.39 90)
			(layer "F.SilkS")
			(effects
				(font
					(size 0.7 0.7)
					(thickness 0.15)
				)
				(justify left bottom)
			)
		)
		(property "Value" "R_10k_0402"
			(at -1.011843 1.772047 90)
			(layer "F.Fab")
			(effects
				(font
					(size 0.7 0.7)
					(thickness 0.15)
				)
				(justify left bottom)
			)
		)
		(property "Datasheet" "https://www.bourns.com/docs/product-datasheets/cr.pdf"
			(at 0 0 90)
			(layer "F.Fab")
			(hide yes)
			(effects
				(font
					(size 1.27 1.27)
					(thickness 0.15)
				)
			)
		)
		(property "Description" "SMD Chip Resistor, 10 kohm, ± 1%, 62.5 mW, 0402 [1005 Metric], Thick Film, General Purpose"
			(at 0 0 90)
			(layer "F.Fab")
			(hide yes)
			(effects
				(font
					(size 1.27 1.27)
					(thickness 0.15)
				)
			)
		)
		(property "Manufacturer" "Bourns"
			(at 0 0 90)
			(unlocked yes)
			(layer "F.Fab")
			(hide yes)
			(effects
				(font
					(size 1 1)
					(thickness 0.15)
				)
			)
		)
		(property "MPN" "CR0402-FX-1002GLF"
			(at 0 0 90)
			(unlocked yes)
			(layer "F.Fab")
			(hide yes)
			(effects
				(font
					(size 1 1)
					(thickness 0.15)
				)
			)
		)
		(property "Val" "10k"
			(at 0 0 90)
			(unlocked yes)
			(layer "F.Fab")
			(hide yes)
			(effects
				(font
					(size 1 1)
					(thickness 0.15)
				)
			)
		)
		(property "License" "Apache-2.0"
			(at 0 0 90)
			(unlocked yes)
			(layer "F.Fab")
			(hide yes)
			(effects
				(font
					(size 1 1)
					(thickness 0.15)
				)
			)
		)
		(property "Author" "Antmicro"
			(at 0 0 90)
			(unlocked yes)
			(layer "F.Fab")
			(hide yes)
			(effects
				(font
					(size 1 1)
					(thickness 0.15)
				)
			)
		)
		(property "Tolerance" "1%"
			(at 0 0 90)
			(unlocked yes)
			(layer "F.Fab")
			(hide yes)
			(effects
				(font
					(size 1 1)
					(thickness 0.15)
				)
			)
		)
		(sheetname "/SoM_Power/")
		(sheetfile "som_power.kicad_sch")
		(attr smd)
		(fp_rect
			(start -0.925 -0.47)
			(end 0.925 0.47)
			(stroke
				(width 0.05)
				(type default)
			)
			(fill no)
			(layer "F.CrtYd")
		)
		(fp_rect
			(start -0.5 -0.25)
			(end 0.5 0.25)
			(stroke
				(width 0.15)
				(type solid)
			)
			(fill no)
			(layer "F.Fab")
		)
		(fp_text user "Author: Antmicro"
			(at -0.95 4.169 90)
			(layer "F.Fab")
			(effects
				(font
					(size 0.7 0.7)
					(thickness 0.15)
				)
				(justify left bottom)
			)
		)
		(fp_text user "License: Apache-2.0"
			(at -0.95 5.169 90)
			(layer "F.Fab")
			(effects
				(font
					(size 0.7 0.7)
					(thickness 0.15)
				)
				(justify left bottom)
			)
		)
		(fp_text user "${REFERENCE}"
			(at -0.95 3.168 90)
			(layer "F.Fab")
			(effects
				(font
					(size 0.7 0.7)
					(thickness 0.15)
				)
				(justify left bottom)
			)
		)
		(pad "1" smd roundrect
			(at -0.48 0 90)
			(size 0.59 0.64)
			(layers "F.Cu" "F.Mask" "F.Paste")
			(roundrect_rratio 0.25)
			(net 1 "GND")
			(pintype "passive")
		)
		(pad "2" smd roundrect
			(at 0.48 0 90)
			(size 0.59 0.64)
			(layers "F.Cu" "F.Mask" "F.Paste")
			(roundrect_rratio 0.25)
			(net 1293 "/DCDC/CARRIER_PWR_ON")
			(pintype "passive")
		)
	)
	(footprint "antmicro-footprints:C_0402_1005Metric"
		(layer "F.Cu")
		(at 219.409001 99.005001 180)
		(descr "Capacitor SMD 0402")
		(tags "capacitor SMD 0402")
		(property "Reference" "C108"
			(at -1.164999 -0.634999 0)
			(layer "F.SilkS")
			(effects
				(font
					(size 0.7 0.7)
					(thickness 0.15)
				)
				(justify right top)
			)
		)
		(property "Value" "C_100n_0402"
			(at -1.022927 2.155213 0)
			(layer "F.Fab")
			(effects
				(font
					(size 0.7 0.7)
					(thickness 0.15)
				)
				(justify right top)
			)
		)
		(property "Datasheet" "https://www.murata.com/products/productdetail?partno=GRM155R61H104KE14%23"
			(at 0 0 0)
			(layer "F.Fab")
			(hide yes)
			(effects
				(font
					(size 1.27 1.27)
					(thickness 0.15)
				)
			)
		)
		(property "Description" "SMD Multilayer Ceramic Capacitor, 0.1 µF, 50 V, 0402 [1005 Metric], ± 10%, X5R, GRM Series"
			(at 0 0 0)
			(layer "F.Fab")
			(hide yes)
			(effects
				(font
					(size 1.27 1.27)
					(thickness 0.15)
				)
			)
		)
		(property "Manufacturer" "Murata"
			(at 0 0 180)
			(unlocked yes)
			(layer "F.Fab")
			(hide yes)
			(effects
				(font
					(size 1 1)
					(thickness 0.15)
				)
			)
		)
		(property "MPN" "GRM155R61H104KE14D"
			(at 0 0 180)
			(unlocked yes)
			(layer "F.Fab")
			(hide yes)
			(effects
				(font
					(size 1 1)
					(thickness 0.15)
				)
			)
		)
		(property "Val" "100n"
			(at 0 0 180)
			(unlocked yes)
			(layer "F.Fab")
			(hide yes)
			(effects
				(font
					(size 1 1)
					(thickness 0.15)
				)
			)
		)
		(property "License" "Apache-2.0"
			(at 0 0 180)
			(unlocked yes)
			(layer "F.Fab")
			(hide yes)
			(effects
				(font
					(size 1 1)
					(thickness 0.15)
				)
			)
		)
		(property "Author" "Antmicro"
			(at 0 0 180)
			(unlocked yes)
			(layer "F.Fab")
			(hide yes)
			(effects
				(font
					(size 1 1)
					(thickness 0.15)
				)
			)
		)
		(property "Voltage" "50V"
			(at 0 0 180)
			(unlocked yes)
			(layer "F.Fab")
			(hide yes)
			(effects
				(font
					(size 1 1)
					(thickness 0.15)
				)
			)
		)
		(property "Dielectric" "X5R"
			(at 0 0 180)
			(unlocked yes)
			(layer "F.Fab")
			(hide yes)
			(effects
				(font
					(size 1 1)
					(thickness 0.15)
				)
			)
		)
		(sheetname "/Recovery USB/")
		(sheetfile "recovery_usb.kicad_sch")
		(attr smd)
		(fp_rect
			(start -0.925 -0.47)
			(end 0.925 0.47)
			(stroke
				(width 0.05)
				(type default)
			)
			(fill no)
			(layer "F.CrtYd")
		)
		(fp_line
			(start 0.504 0.248)
			(end -0.494 0.248)
			(stroke
				(width 0.15)
				(type solid)
			)
			(layer "F.Fab")
		)
		(fp_line
			(start 0.504 -0.25)
			(end 0.504 0.248)
			(stroke
				(width 0.15)
				(type solid)
			)
			(layer "F.Fab")
		)
		(fp_line
			(start -0.494 0.248)
			(end -0.494 -0.25)
			(stroke
				(width 0.15)
				(type solid)
			)
			(layer "F.Fab")
		)
		(fp_line
			(start -0.494 -0.25)
			(end 0.504 -0.25)
			(stroke
				(width 0.15)
				(type solid)
			)
			(layer "F.Fab")
		)
		(fp_text user "Author: Antmicro"
			(at -0.939 3.399 0)
			(layer "F.Fab")
			(effects
				(font
					(size 0.7 0.7)
					(thickness 0.15)
				)
				(justify right top)
			)
		)
		(fp_text user "License: Apache-2.0"
			(at -0.939 5.799 0)
			(layer "F.Fab")
			(effects
				(font
					(size 0.7 0.7)
					(thickness 0.15)
				)
				(justify right top)
			)
		)
		(fp_text user "${REFERENCE}"
			(at -0.939 4.599 0)
			(layer "F.Fab")
			(effects
				(font
					(size 0.7 0.7)
					(thickness 0.15)
				)
				(justify right top)
			)
		)
		(pad "1" smd roundrect
			(at -0.48 0 180)
			(size 0.59 0.64)
			(layers "F.Cu" "F.Mask" "F.Paste")
			(roundrect_rratio 0.25)
			(net 241 "/Recovery USB/USBC2_CONN_TX2_N")
			(pintype "passive")
		)
		(pad "2" smd roundrect
			(at 0.48 0 180)
			(size 0.59 0.64)
			(layers "F.Cu" "F.Mask" "F.Paste")
			(roundrect_rratio 0.25)
			(net 237 "/Recovery USB/USBC2_TX2_N")
			(pintype "passive")
		)
	)
	(footprint "antmicro-footprints:C_0402_1005Metric"
		(layer "F.Cu")
		(at 67.4 97.075 90)
		(descr "Capacitor SMD 0402")
		(tags "capacitor SMD 0402")
		(property "Reference" "C162"
			(at -1.58 1.37 90)
			(layer "F.SilkS")
			(effects
				(font
					(size 0.7 0.7)
					(thickness 0.15)
				)
				(justify left bottom)
			)
		)
		(property "Value" "C_100n_0402"
			(at -1.022927 2.155213 90)
			(layer "F.Fab")
			(effects
				(font
					(size 0.7 0.7)
					(thickness 0.15)
				)
				(justify left bottom)
			)
		)
		(property "Datasheet" "https://www.murata.com/products/productdetail?partno=GRM155R61H104KE14%23"
			(at 0 0 90)
			(layer "F.Fab")
			(hide yes)
			(effects
				(font
					(size 1.27 1.27)
					(thickness 0.15)
				)
			)
		)
		(property "Description" "SMD Multilayer Ceramic Capacitor, 0.1 µF, 50 V, 0402 [1005 Metric], ± 10%, X5R, GRM Series"
			(at 0 0 90)
			(layer "F.Fab")
			(hide yes)
			(effects
				(font
					(size 1.27 1.27)
					(thickness 0.15)
				)
			)
		)
		(property "Manufacturer" "Murata"
			(at 0 0 90)
			(unlocked yes)
			(layer "F.Fab")
			(hide yes)
			(effects
				(font
					(size 1 1)
					(thickness 0.15)
				)
			)
		)
		(property "MPN" "GRM155R61H104KE14D"
			(at 0 0 90)
			(unlocked yes)
			(layer "F.Fab")
			(hide yes)
			(effects
				(font
					(size 1 1)
					(thickness 0.15)
				)
			)
		)
		(property "Val" "100n"
			(at 0 0 90)
			(unlocked yes)
			(layer "F.Fab")
			(hide yes)
			(effects
				(font
					(size 1 1)
					(thickness 0.15)
				)
			)
		)
		(property "License" "Apache-2.0"
			(at 0 0 90)
			(unlocked yes)
			(layer "F.Fab")
			(hide yes)
			(effects
				(font
					(size 1 1)
					(thickness 0.15)
				)
			)
		)
		(property "Author" "Antmicro"
			(at 0 0 90)
			(unlocked yes)
			(layer "F.Fab")
			(hide yes)
			(effects
				(font
					(size 1 1)
					(thickness 0.15)
				)
			)
		)
		(property "Voltage" "50V"
			(at 0 0 90)
			(unlocked yes)
			(layer "F.Fab")
			(hide yes)
			(effects
				(font
					(size 1 1)
					(thickness 0.15)
				)
			)
		)
		(property "Dielectric" "X5R"
			(at 0 0 90)
			(unlocked yes)
			(layer "F.Fab")
			(hide yes)
			(effects
				(font
					(size 1 1)
					(thickness 0.15)
				)
			)
		)
		(sheetname "/CSI/")
		(sheetfile "csi.kicad_sch")
		(attr smd)
		(fp_poly
			(pts
				(xy -0.925 -0.47) (xy -0.925 0.47) (xy 0.925 0.47) (xy 0.925 -0.47)
			)
			(stroke
				(width 0.05)
				(type default)
			)
			(fill no)
			(layer "F.CrtYd")
		)
		(fp_line
			(start 0.504 -0.25)
			(end 0.504 0.248)
			(stroke
				(width 0.15)
				(type solid)
			)
			(layer "F.Fab")
		)
		(fp_line
			(start -0.494 -0.25)
			(end 0.504 -0.25)
			(stroke
				(width 0.15)
				(type solid)
			)
			(layer "F.Fab")
		)
		(fp_line
			(start 0.504 0.248)
			(end -0.494 0.248)
			(stroke
				(width 0.15)
				(type solid)
			)
			(layer "F.Fab")
		)
		(fp_line
			(start -0.494 0.248)
			(end -0.494 -0.25)
			(stroke
				(width 0.15)
				(type solid)
			)
			(layer "F.Fab")
		)
		(fp_text user "${REFERENCE}"
			(at -0.939 4.599 90)
			(layer "F.Fab")
			(effects
				(font
					(size 0.7 0.7)
					(thickness 0.15)
				)
				(justify left bottom)
			)
		)
		(fp_text user "License: Apache-2.0"
			(at -0.939 5.799 90)
			(layer "F.Fab")
			(effects
				(font
					(size 0.7 0.7)
					(thickness 0.15)
				)
				(justify left bottom)
			)
		)
		(fp_text user "Author: Antmicro"
			(at -0.939 3.399 90)
			(layer "F.Fab")
			(effects
				(font
					(size 0.7 0.7)
					(thickness 0.15)
				)
				(justify left bottom)
			)
		)
		(pad "1" smd roundrect
			(at -0.48 0 90)
			(size 0.59 0.64)
			(layers "F.Cu" "F.Mask" "F.Paste")
			(roundrect_rratio 0.25)
			(net 1 "GND")
			(pintype "passive")
		)
		(pad "2" smd roundrect
			(at 0.48 0 90)
			(size 0.59 0.64)
			(layers "F.Cu" "F.Mask" "F.Paste")
			(roundrect_rratio 0.25)
			(net 11 "+1V8")
			(pintype "passive")
		)
	)
	(footprint "antmicro-footprints:SW_KMR211NGLFS_SMD"
		(layer "F.Cu")
		(at 191 60.6)
		(property "Reference" "S3"
			(at -1.4 2 0)
			(layer "F.SilkS")
			(hide yes)
			(effects
				(font
					(size 0.7 0.7)
					(thickness 0.15)
				)
				(justify right top)
			)
		)
		(property "Value" "SW_KMR211NGLFS_SMD"
			(at 0 2.8 0)
			(layer "F.Fab")
			(effects
				(font
					(size 0.7 0.7)
					(thickness 0.15)
				)
				(justify left bottom)
			)
		)
		(property "Datasheet" "http://www.farnell.com/datasheets/2631211.pdf"
			(at 0 0 0)
			(layer "F.Fab")
			(hide yes)
			(effects
				(font
					(size 1.27 1.27)
					(thickness 0.15)
				)
			)
		)
		(property "Description" "Tactile Switch, KMR 2 Series, Top Actuated, Surface Mount, Oval Button, 120 gf, 50mA at 32VDC"
			(at 0 0 0)
			(layer "F.Fab")
			(hide yes)
			(effects
				(font
					(size 1.27 1.27)
					(thickness 0.15)
				)
			)
		)
		(property "MPN" "KMR211NGLFS"
			(at 0 0 0)
			(unlocked yes)
			(layer "F.Fab")
			(hide yes)
			(effects
				(font
					(size 1 1)
					(thickness 0.15)
				)
			)
		)
		(property "Manufacturer" "C&K"
			(at 0 0 0)
			(unlocked yes)
			(layer "F.Fab")
			(hide yes)
			(effects
				(font
					(size 1 1)
					(thickness 0.15)
				)
			)
		)
		(property "Author" "Antmicro"
			(at 0 0 0)
			(unlocked yes)
			(layer "F.Fab")
			(hide yes)
			(effects
				(font
					(size 1 1)
					(thickness 0.15)
				)
			)
		)
		(property "License" "Apache-2.0"
			(at 0 0 0)
			(unlocked yes)
			(layer "F.Fab")
			(hide yes)
			(effects
				(font
					(size 1 1)
					(thickness 0.15)
				)
			)
		)
		(sheetname "/Peripherals/")
		(sheetfile "peripherals.kicad_sch")
		(attr smd)
		(fp_line
			(start -2.1 -1.6)
			(end -2.1 -1.499)
			(stroke
				(width 0.15)
				(type solid)
			)
			(layer "F.SilkS")
		)
		(fp_line
			(start -2.1 1.601)
			(end -2.1 1.48)
			(stroke
				(width 0.15)
				(type solid)
			)
			(layer "F.SilkS")
		)
		(fp_line
			(start 2.101 -1.6)
			(end -2.1 -1.6)
			(stroke
				(width 0.15)
				(type solid)
			)
			(layer "F.SilkS")
		)
		(fp_line
			(start 2.101 -1.58)
			(end 2.101 -1.459)
			(stroke
				(width 0.15)
				(type solid)
			)
			(layer "F.SilkS")
		)
		(fp_line
			(start 2.101 1.601)
			(end -2.1 1.601)
			(stroke
				(width 0.15)
				(type solid)
			)
			(layer "F.SilkS")
		)
		(fp_line
			(start 2.101 1.601)
			(end 2.101 1.48)
			(stroke
				(width 0.15)
				(type solid)
			)
			(layer "F.SilkS")
		)
		(fp_poly
			(pts
				(xy 2.751 1.75) (xy 2.751 -1.749) (xy -2.748 -1.749) (xy -2.748 1.749999)
			)
			(stroke
				(width 0.05)
				(type solid)
			)
			(fill no)
			(layer "F.CrtYd")
		)
		(fp_line
			(start -2.1 -1.6)
			(end -2.1 1.601)
			(stroke
				(width 0.15)
				(type solid)
			)
			(layer "F.Fab")
		)
		(fp_line
			(start -2.1 1.601)
			(end 2.101 1.601)
			(stroke
				(width 0.15)
				(type solid)
			)
			(layer "F.Fab")
		)
		(fp_line
			(start -0.248 -0.8)
			(end 0.25 -0.8)
			(stroke
				(width 0.15)
				(type solid)
			)
			(layer "F.Fab")
		)
		(fp_line
			(start 0.25 0.802)
			(end -0.248 0.802)
			(stroke
				(width 0.15)
				(type solid)
			)
			(layer "F.Fab")
		)
		(fp_line
			(start 2.101 -1.6)
			(end -2.1 -1.6)
			(stroke
				(width 0.15)
				(type solid)
			)
			(layer "F.Fab")
		)
		(fp_line
			(start 2.101 1.601)
			(end 2.101 -1.6)
			(stroke
				(width 0.15)
				(type solid)
			)
			(layer "F.Fab")
		)
		(fp_arc
			(start -0.248 0.802)
			(mid -1.050001 0.001)
			(end -0.248 -0.8)
			(stroke
				(width 0.15)
				(type solid)
			)
			(layer "F.Fab")
		)
		(fp_arc
			(start 0.25 -0.8)
			(mid 1.051001 0.001)
			(end 0.25 0.802)
			(stroke
				(width 0.15)
				(type solid)
			)
			(layer "F.Fab")
		)
		(fp_text user "Author: Antmicro"
			(at -3 5.5 0)
			(layer "F.Fab")
			(effects
				(font
					(size 0.7 0.7)
					(thickness 0.15)
				)
				(justify left bottom)
			)
		)
		(fp_text user "License: Apache-2.0"
			(at -3 6.75 0)
			(layer "F.Fab")
			(effects
				(font
					(size 0.7 0.7)
					(thickness 0.15)
				)
				(justify left bottom)
			)
		)
		(fp_text user "${REFERENCE}"
			(at -3 4.25 0)
			(layer "F.Fab")
			(effects
				(font
					(size 0.7 0.7)
					(thickness 0.15)
				)
				(justify left bottom)
			)
		)
		(pad "1" smd rect
			(at -2.048 -0.8 180)
			(size 0.9 1)
			(layers "F.Cu" "F.Mask" "F.Paste")
			(net 356 "/Expansion connector/GPIO.USER_BTN1")
			(pinfunction "1")
			(pintype "passive")
		)
		(pad "2" smd rect
			(at 2.049999 -0.8 180)
			(size 0.9 1)
			(layers "F.Cu" "F.Mask" "F.Paste")
			(net 356 "/Expansion connector/GPIO.USER_BTN1")
			(pinfunction "2")
			(pintype "passive")
		)
		(pad "3" smd rect
			(at -2.048 0.802 180)
			(size 0.9 1)
			(layers "F.Cu" "F.Mask" "F.Paste")
			(net 1 "GND")
			(pinfunction "3")
			(pintype "passive")
		)
		(pad "4" smd rect
			(at 2.05 0.802001 180)
			(size 0.9 1)
			(layers "F.Cu" "F.Mask" "F.Paste")
			(net 1 "GND")
			(pinfunction "4")
			(pintype "passive")
		)
	)
)
